.HEADER
BOARD_FILE 3.0 "Creo Elements/Pro 5.0 M210" 2017/03/22.10:07:02 3
16316-SD                                MM        
.END_HEADER
.BOARD_OUTLINE  MCAD
1.60000             
         0            85.00250           143.00000             0.00000
         0            83.00250           145.00000            90.00000
         0             2.00000           145.00000             0.00000
         0             0.00000           143.00000            90.00000
         0             0.00000             2.00000             0.00000
         0             2.00000             0.00000            90.00000
         0           208.00000             0.00000             0.00000
         0           210.00000             2.00000            90.00000
         0           210.00000           143.00000             0.00000
         0           208.00000           145.00000            90.00000
         0           127.00250           145.00000             0.00000
         0           125.00250           143.00000            90.00000
         0           125.00250           132.26373             0.00000
         0           120.79230           127.32650           -80.91151
         0           112.50000           126.00000             0.00000
         0            97.50000           126.00000             0.00000
         0            89.21270           127.32570             0.00000
         0            85.00250           132.26293           -80.91151
         0            85.00250           143.00000             0.00000
         1           202.35000           131.43000             0.00000
         1           198.65000           131.43000          -180.00000
         1           202.35000           131.43000          -180.00000
         2            11.35000           131.43000             0.00000
         2             7.65000           131.43000          -180.00000
         2            11.35000           131.43000          -180.00000
         3           201.55000           135.93000             0.00000
         3           199.45000           135.93000          -180.00000
         3           201.55000           135.93000          -180.00000
         4            10.55000           135.93000             0.00000
         4             8.45000           135.93000          -180.00000
         4            10.55000           135.93000          -180.00000
         5           201.27500           126.93000             0.00000
         5           199.72500           126.93000          -180.00000
         5           201.27500           126.93000          -180.00000
         6            10.27500           126.93000             0.00000
         6             8.72500           126.93000          -180.00000
         6            10.27500           126.93000          -180.00000
         7           200.00000            50.50000             0.00000
         7           197.00000            50.50000          -180.00000
         7           200.00000            50.50000          -180.00000
         8           153.00000            29.50000             0.00000
         8           150.00000            29.50000          -180.00000
         8           153.00000            29.50000          -180.00000
         9           136.50000            94.31000             0.00000
         9           133.50000            94.31000          -180.00000
         9           136.50000            94.31000          -180.00000
        10            96.50000            39.68000             0.00000
        10            93.50000            39.68000          -180.00000
        10            96.50000            39.68000          -180.00000
        11            30.68500             3.70000             0.00000
        11            28.27500             3.70000          -180.00000
        11            30.68500             3.70000          -180.00000
        12            30.75500             9.92000             0.00000
        12            28.20500             9.92000          -180.00000
        12            30.75500             9.92000          -180.00000
        13           136.75000           135.00000             0.00000
        13           133.25000           135.00000          -180.00000
        13           136.75000           135.00000          -180.00000
        14            76.75000           135.00000             0.00000
        14            73.25000           135.00000          -180.00000
        14            76.75000           135.00000          -180.00000
.END_BOARD_OUTLINE
.DRILLED_HOLES
.END_DRILLED_HOLES
.PLACE_KEEPOUT      UNOWNED
TOP 0.20000        
         0           208.00000             0.00000             0.00000
         0           210.00000             2.00000            90.00000
         0           210.00000           143.00000             0.00000
         0           208.00000           145.00000            90.00000
         0           205.00000           145.00000             0.00000
         0           205.00000             0.00000             0.00000
         0           208.00000             0.00000             0.00000
.END_PLACE_KEEPOUT
.PLACE_KEEPOUT      UNOWNED
TOP 0.20000        
         0             5.00000           145.00000             0.00000
         0             5.00000             0.00000             0.00000
         0             2.00000             0.00000             0.00000
         0             0.00000             2.00000           -90.00000
         0             0.00000           143.00000             0.00000
         0             2.00000           145.00000           -90.00000
         0             5.00000           145.00000             0.00000
.END_PLACE_KEEPOUT
.PLACE_KEEPOUT      UNOWNED
TOP 0.00000        
         0           190.00000           125.00000             0.00000
         0           190.00000           105.00000             0.00000
         0           205.00000           105.00000             0.00000
         0           205.00000           123.63577             0.00000
         0           205.00000           139.22423          -240.00000
         0           205.00000           145.00000             0.00000
         0           127.00250           145.00000             0.00000
         0           125.00250           143.00000            90.00000
         0           125.00250           132.26373             0.00000
         0           120.79230           127.32650           -80.91151
         0           112.50000           126.00000             0.00000
         0            97.50000           126.00000             0.00000
         0            89.21270           127.32570             0.00000
         0            85.00250           132.26293           -80.91151
         0            85.00250           143.00000             0.00000
         0            83.00250           145.00000            90.00000
         0             5.00000           145.00000             0.00000
         0             5.00000           139.22423             0.00000
         0             5.00000           123.63577          -240.00000
         0             5.00000           105.00000             0.00000
         0            20.00000           105.00000             0.00000
         0            20.00000           125.00000             0.00000
         0            85.00250           125.00000             0.00000
         0            85.00250           119.00000             0.00000
         0           125.00250           119.00000             0.00000
         0           125.00250           125.00000             0.00000
         0           190.00000           125.00000             0.00000
.END_PLACE_KEEPOUT
.PLACE_KEEPOUT      UNOWNED
TOP 0.00000        
         0            79.75000           135.00000             0.00000
         0            70.25000           135.00000           180.00000
         0            79.75000           135.00000           180.00000
.END_PLACE_KEEPOUT
.PLACE_KEEPOUT      UNOWNED
TOP 0.00000        
         0           139.75000           135.00000             0.00000
         0           130.25000           135.00000           180.00000
         0           139.75000           135.00000           180.00000
.END_PLACE_KEEPOUT
.PLACE_KEEPOUT      UNOWNED
TOP 0.00000        
         0            92.00000            39.68000             0.00000
         0            98.00000            39.68000           180.00000
         0            92.00000            39.68000           180.00000
.END_PLACE_KEEPOUT
.PLACE_KEEPOUT      UNOWNED
TOP 0.00000        
         0           195.50000            50.50000             0.00000
         0           201.50000            50.50000           180.00000
         0           195.50000            50.50000           180.00000
.END_PLACE_KEEPOUT
.PLACE_KEEPOUT      UNOWNED
TOP 0.00000        
         0           148.50000            29.50000             0.00000
         0           154.50000            29.50000           180.00000
         0           148.50000            29.50000           180.00000
.END_PLACE_KEEPOUT
.PLACE_KEEPOUT      UNOWNED
TOP 0.00000        
         0           205.00000           139.22423             0.00000
         0           205.00000           123.63577           240.00000
         0           205.00000           139.22423             0.00000
.END_PLACE_KEEPOUT
.PLACE_KEEPOUT      UNOWNED
TOP 0.00000        
         0             5.00000           123.63577             0.00000
         0             5.00000           139.22423           240.00000
         0             5.00000           123.63577             0.00000
.END_PLACE_KEEPOUT
.PLACE_KEEPOUT      UNOWNED
TOP 0.00000        
         0            70.25000           135.00000             0.00000
         0            79.75000           135.00000           180.00000
         0            70.25000           135.00000           180.00000
.END_PLACE_KEEPOUT
.PLACE_KEEPOUT      UNOWNED
TOP 0.00000        
         0           130.25000           135.00000             0.00000
         0           139.75000           135.00000           180.00000
         0           130.25000           135.00000           180.00000
.END_PLACE_KEEPOUT
.PLACE_KEEPOUT      UNOWNED
TOP 0.00000        
         0           132.00000            94.31000             0.00000
         0           138.00000            94.31000           180.00000
         0           132.00000            94.31000           180.00000
.END_PLACE_KEEPOUT
.PLACE_KEEPOUT      UNOWNED
TOP 1.00000        
         0           147.00000            71.00000             0.00000
         0           203.00000            71.00000             0.00000
         0           203.00000            19.00000             0.00000
         0           147.00000            19.00000             0.00000
         0           147.00000            71.00000             0.00000
.END_PLACE_KEEPOUT
.PLACE_KEEPOUT      UNOWNED
TOP 1.00000        
         0           201.50000            50.50000             0.00000
         0           195.50000            50.50000           180.00000
         0           201.50000            50.50000           180.00000
.END_PLACE_KEEPOUT
.PLACE_KEEPOUT      UNOWNED
TOP 1.00000        
         0           154.50000            29.50000             0.00000
         0           148.50000            29.50000           180.00000
         0           154.50000            29.50000           180.00000
.END_PLACE_KEEPOUT
.PLACE_KEEPOUT      UNOWNED
TOP 0.60000        
         0           141.00000            33.68500             0.00000
         0            89.00000            33.68500             0.00000
         0            89.00000           100.31500             0.00000
         0           141.00000           100.31500             0.00000
         0           141.00000            33.68500             0.00000
.END_PLACE_KEEPOUT
.PLACE_KEEPOUT      UNOWNED
TOP 0.60000        
         0            92.00000            39.68000             0.00000
         0            98.00000            39.68000           180.00000
         0            92.00000            39.68000           180.00000
.END_PLACE_KEEPOUT
.PLACE_KEEPOUT      UNOWNED
TOP 0.60000        
         0           138.00000            94.31000             0.00000
         0           132.00000            94.31000           180.00000
         0           138.00000            94.31000           180.00000
.END_PLACE_KEEPOUT
.PLACE_KEEPOUT      UNOWNED
TOP 15.00000       
         0           205.00000           105.00000             0.00000
         0           205.00000             0.00000             0.00000
         0             5.00000             0.00000             0.00000
         0             5.00000           105.00000             0.00000
         0            20.00000           105.00000             0.00000
         0            20.00000           125.00000             0.00000
         0            85.00250           125.00000             0.00000
         0            85.00250           119.00000             0.00000
         0           125.00250           119.00000             0.00000
         0           125.00250           125.00000             0.00000
         0           190.00000           125.00000             0.00000
         0           190.00000           105.00000             0.00000
         0           205.00000           105.00000             0.00000
.END_PLACE_KEEPOUT
.PLACE_KEEPOUT      UNOWNED
TOP 15.00000       
         0           141.00000            33.68500             0.00000
         0            89.00000            33.68500             0.00000
         0            89.00000           100.31500             0.00000
         0           141.00000           100.31500             0.00000
         0           141.00000            33.68500             0.00000
.END_PLACE_KEEPOUT
.PLACE_KEEPOUT      UNOWNED
TOP 15.00000       
         0           203.00000            71.00000             0.00000
         0           203.00000            19.00000             0.00000
         0           147.00000            19.00000             0.00000
         0           147.00000            71.00000             0.00000
         0           203.00000            71.00000             0.00000
.END_PLACE_KEEPOUT
.PLACE_KEEPOUT      UNOWNED
BOTTOM 0.00000        
         0           138.00000            94.31000             0.00000
         0           132.00000            94.31000          -180.00000
         0           138.00000            94.31000          -180.00000
.END_PLACE_KEEPOUT
.PLACE_KEEPOUT      UNOWNED
BOTTOM 0.00000        
         0           201.50000            50.50000             0.00000
         0           195.50000            50.50000          -180.00000
         0           201.50000            50.50000          -180.00000
.END_PLACE_KEEPOUT
.PLACE_KEEPOUT      UNOWNED
BOTTOM 0.00000        
         0           154.50000            29.50000             0.00000
         0           148.50000            29.50000          -180.00000
         0           154.50000            29.50000          -180.00000
.END_PLACE_KEEPOUT
.PLACE_KEEPOUT      UNOWNED
BOTTOM 0.00000        
         0            98.00000            39.68000             0.00000
         0            92.00000            39.68000          -180.00000
         0            98.00000            39.68000          -180.00000
.END_PLACE_KEEPOUT
.PLACE_KEEPOUT      UNOWNED
BOTTOM 0.00000        
         0            32.98090             9.92500             0.00000
         0            25.98090             9.92500          -180.00000
         0            32.98090             9.92500          -180.00000
.END_PLACE_KEEPOUT
.PLACE_KEEPOUT      UNOWNED
BOTTOM 0.00000        
         0             5.00000           139.22423             0.00000
         0             5.00000           123.63577          -240.00000
         0             5.00000           139.22423             0.00000
.END_PLACE_KEEPOUT
.PLACE_KEEPOUT      UNOWNED
BOTTOM 0.00000        
         0           205.00000           123.63577             0.00000
         0           205.00000           139.22423          -240.00000
         0           205.00000           123.63577             0.00000
.END_PLACE_KEEPOUT
.PLACE_KEEPOUT      UNOWNED
BOTTOM 0.00000        
         0           139.75000           135.00000             0.00000
         0           130.25000           135.00000          -180.00000
         0           139.75000           135.00000          -180.00000
.END_PLACE_KEEPOUT
.PLACE_KEEPOUT      UNOWNED
BOTTOM 0.00000        
         0            79.75000           135.00000             0.00000
         0            70.25000           135.00000          -180.00000
         0            79.75000           135.00000          -180.00000
.END_PLACE_KEEPOUT
.PLACE_KEEPOUT      UNOWNED
BOTTOM 0.20000        
         0             5.00000             0.00000             0.00000
         0             2.00000             0.00000             0.00000
         0             0.00000             2.00000           -90.00000
         0             0.00000           143.00000             0.00000
         0             2.00000           145.00000           -90.00000
         0             5.00000           145.00000             0.00000
         0             5.00000             0.00000             0.00000
.END_PLACE_KEEPOUT
.PLACE_KEEPOUT      UNOWNED
BOTTOM 0.20000        
         0           208.00000             0.00000             0.00000
         0           205.00000             0.00000             0.00000
         0           205.00000           145.00000             0.00000
         0           208.00000           145.00000             0.00000
         0           210.00000           143.00000           -90.00000
         0           210.00000             2.00000             0.00000
         0           208.00000             0.00000           -90.00000
.END_PLACE_KEEPOUT
.PLACE_KEEPOUT      UNOWNED
BOTTOM 0.00000        
         0             5.00000           139.22423             0.00000
         0             5.00000           123.63577          -240.00000
         0             5.00000           105.00000             0.00000
         0            20.00000           105.00000             0.00000
         0            20.00000           125.00000             0.00000
         0            85.00250           125.00000             0.00000
         0            85.00250           119.00000             0.00000
         0           125.00250           119.00000             0.00000
         0           125.00250           125.00000             0.00000
         0           190.00000           125.00000             0.00000
         0           190.00000           105.00000             0.00000
         0           205.00000           105.00000             0.00000
         0           205.00000           123.63577             0.00000
         0           205.00000           139.22423          -240.00000
         0           205.00000           145.00000             0.00000
         0           127.00250           145.00000             0.00000
         0           125.00250           143.00000            90.00000
         0           125.00250           132.26373             0.00000
         0           120.79230           127.32650           -80.91151
         0           112.50000           126.00000             0.00000
         0            97.50000           126.00000             0.00000
         0            89.21270           127.32570             0.00000
         0            85.00250           132.26293           -80.91151
         0            85.00250           143.00000             0.00000
         0            83.00250           145.00000            90.00000
         0             5.00000           145.00000             0.00000
         0             5.00000           139.22423             0.00000
.END_PLACE_KEEPOUT
.PLACE_KEEPOUT      UNOWNED
BOTTOM 0.00000        
         0           130.25000           135.00000             0.00000
         0           139.75000           135.00000          -180.00000
         0           130.25000           135.00000          -180.00000
.END_PLACE_KEEPOUT
.PLACE_KEEPOUT      UNOWNED
BOTTOM 0.00000        
         0            70.25000           135.00000             0.00000
         0            79.75000           135.00000          -180.00000
         0            70.25000           135.00000          -180.00000
.END_PLACE_KEEPOUT
.PLACE_KEEPOUT      UNOWNED
BOTTOM 5.00000        
         0            85.00250           125.00000             0.00000
         0            85.00250           121.00000             0.00000
         0            87.00250           119.00000            90.00000
         0           123.00250           119.00000             0.00000
         0           125.00250           121.00000            90.00000
         0           125.00250           125.00000             0.00000
         0           190.00000           125.00000             0.00000
         0           190.00000           105.00000             0.00000
         0           205.00000           105.00000             0.00000
         0           205.00000             0.00000             0.00000
         0             5.00000             0.00000             0.00000
         0             5.00000           105.00000             0.00000
         0            20.00000           105.00000             0.00000
         0            20.00000           125.00000             0.00000
         0            85.00250           125.00000             0.00000
.END_PLACE_KEEPOUT
.PLACE_KEEPOUT      UNOWNED
BOTTOM 5.00000        
         0            92.00000            39.68000             0.00000
         0            98.00000            39.68000          -180.00000
         0            92.00000            39.68000          -180.00000
.END_PLACE_KEEPOUT
.PLACE_KEEPOUT      UNOWNED
BOTTOM 5.00000        
         0           132.00000            94.31000             0.00000
         0           138.00000            94.31000          -180.00000
         0           132.00000            94.31000          -180.00000
.END_PLACE_KEEPOUT
.PLACE_KEEPOUT      UNOWNED
BOTTOM 5.00000        
         0           195.50000            50.50000             0.00000
         0           201.50000            50.50000          -180.00000
         0           195.50000            50.50000          -180.00000
.END_PLACE_KEEPOUT
.PLACE_KEEPOUT      UNOWNED
BOTTOM 5.00000        
         0           148.50000            29.50000             0.00000
         0           154.50000            29.50000          -180.00000
         0           148.50000            29.50000          -180.00000
.END_PLACE_KEEPOUT
.PLACE_KEEPOUT      UNOWNED
BOTTOM 5.00000        
         0            25.98090             9.92500             0.00000
         0            32.98090             9.92500          -180.00000
         0            25.98090             9.92500          -180.00000
.END_PLACE_KEEPOUT
.PLACE_KEEPOUT      UNOWNED
BOTTOM 5.00000        
         0            30.68500             3.70000             0.00000
         0            28.27500             3.70000          -180.00000
         0            30.68500             3.70000          -180.00000
.END_PLACE_KEEPOUT
.ROUTE_KEEPOUT  UNOWNED
TOP
         0           132.00000            94.31000             0.00000
         0           138.00000            94.31000           180.00000
         0           132.00000            94.31000           180.00000
.END_ROUTE_KEEPOUT
.ROUTE_KEEPOUT  UNOWNED
TOP
         0           195.50000            50.50000             0.00000
         0           201.50000            50.50000           180.00000
         0           195.50000            50.50000           180.00000
.END_ROUTE_KEEPOUT
.ROUTE_KEEPOUT  UNOWNED
TOP
         0           148.50000            29.50000             0.00000
         0           154.50000            29.50000           180.00000
         0           148.50000            29.50000           180.00000
.END_ROUTE_KEEPOUT
.ROUTE_KEEPOUT  UNOWNED
TOP
         0            92.00000            39.68000             0.00000
         0            98.00000            39.68000           180.00000
         0            92.00000            39.68000           180.00000
.END_ROUTE_KEEPOUT
.ROUTE_KEEPOUT  UNOWNED
TOP
         0           205.00000           139.22423             0.00000
         0           205.00000           123.63577           240.00000
         0           205.00000           139.22423             0.00000
.END_ROUTE_KEEPOUT
.ROUTE_KEEPOUT  UNOWNED
TOP
         0             5.00000           123.63577             0.00000
         0             5.00000           139.22423           240.00000
         0             5.00000           123.63577             0.00000
.END_ROUTE_KEEPOUT
.ROUTE_KEEPOUT  UNOWNED
TOP
         0            70.25000           135.00000             0.00000
         0            79.75000           135.00000           180.00000
         0            70.25000           135.00000           180.00000
.END_ROUTE_KEEPOUT
.ROUTE_KEEPOUT  UNOWNED
TOP
         0           130.25000           135.00000             0.00000
         0           139.75000           135.00000           180.00000
         0           130.25000           135.00000           180.00000
.END_ROUTE_KEEPOUT
.ROUTE_KEEPOUT  UNOWNED
BOTTOM
         0            25.98090             9.92500             0.00000
         0            32.98090             9.92500          -180.00000
         0            25.98090             9.92500          -180.00000
.END_ROUTE_KEEPOUT
.ROUTE_KEEPOUT  UNOWNED
BOTTOM
         0           201.50000            50.50000             0.00000
         0           195.50000            50.50000          -180.00000
         0           201.50000            50.50000          -180.00000
.END_ROUTE_KEEPOUT
.ROUTE_KEEPOUT  UNOWNED
BOTTOM
         0           154.50000            29.50000             0.00000
         0           148.50000            29.50000          -180.00000
         0           154.50000            29.50000          -180.00000
.END_ROUTE_KEEPOUT
.ROUTE_KEEPOUT  UNOWNED
BOTTOM
         0            98.00000            39.68000             0.00000
         0            92.00000            39.68000          -180.00000
         0            98.00000            39.68000          -180.00000
.END_ROUTE_KEEPOUT
.ROUTE_KEEPOUT  UNOWNED
BOTTOM
         0           138.00000            94.31000             0.00000
         0           132.00000            94.31000          -180.00000
         0           138.00000            94.31000          -180.00000
.END_ROUTE_KEEPOUT
.ROUTE_KEEPOUT  UNOWNED
BOTTOM
         0             5.00000           139.22423             0.00000
         0             5.00000           123.63577          -240.00000
         0             5.00000           139.22423             0.00000
.END_ROUTE_KEEPOUT
.ROUTE_KEEPOUT  UNOWNED
BOTTOM
         0           205.00000           123.63577             0.00000
         0           205.00000           139.22423          -240.00000
         0           205.00000           123.63577             0.00000
.END_ROUTE_KEEPOUT
.ROUTE_KEEPOUT  UNOWNED
BOTTOM
         0           139.75000           135.00000             0.00000
         0           130.25000           135.00000          -180.00000
         0           139.75000           135.00000          -180.00000
.END_ROUTE_KEEPOUT
.ROUTE_KEEPOUT  UNOWNED
BOTTOM
         0            79.75000           135.00000             0.00000
         0            70.25000           135.00000          -180.00000
         0            79.75000           135.00000          -180.00000
.END_ROUTE_KEEPOUT
.PLACEMENT
020_80963_0001 020_80963_0001 CN2           
86.00000       3.80000        -0.00000       0.00000        TOP       PLACED         
020_80777_0001 020_80777_0001 CN1           
37.00000       5.03000        -0.00000       0.00000        TOP       PLACED         
020_80815_0011 020_80815_0011 CN6           
180.00000      3.80000        -0.00000       0.00000        TOP       PLACED         
20_82057_036   20_82057_036   MSAS1         
105.00000      117.00000      -0.00000       180.00000      TOP       PLACED         
19-000387$AA   19-000387$AA   U2            
175.00000      40.00000       0.00000        0.00000        TOP       PLACED         
71_03X48_00U   71_03X48_00U   U1            
115.00000      67.00000       0.00000        0.00000        TOP       PLACED         
21_D0358_207   21_D0358_207   DB1           
30.00000       120.00000      -0.00000       180.00000      TOP       PLACED         
ZZ_00PAD_QL1   ZZ_00PAD_QL1   RHOLE1        
200.50000      131.43000      0.00000        0.00000        TOP       PLACED         
ZZ_00PAD_QM1   ZZ_00PAD_QM1   LHOLE1        
9.50000        131.43000      0.00000        0.00000        TOP       PLACED         
.END_PLACEMENT
